(kicad_pcb
	(version 20260206)
	(generator "pcbnew")
	(generator_version "10.0")
	(general
		(thickness 1.6)
		(legacy_teardrops no)
	)
	(paper "A4")
	(title_block
		(title "peb — Lightning_PEB_BRD.brd")
		(comment 1 "Lightning (Wiwynn / Facebook NVMe JBOF) / footprints 814-820 of 2563")
	)
	(layers
		(0 "F.Cu" signal "TOP")
		(4 "In1.Cu" signal "L2GND")
		(6 "In2.Cu" signal "L3")
		(8 "In3.Cu" signal "L4VCC")
		(10 "In4.Cu" signal "L5VCC")
		(12 "In5.Cu" signal "L6")
		(14 "In6.Cu" signal "L7GND")
		(2 "B.Cu" signal "BOTTOM")
		(9 "F.Adhes" user "F.Adhesive")
		(11 "B.Adhes" user "B.Adhesive")
		(13 "F.Paste" user "Package Geometry/Pastemask Top")
		(15 "B.Paste" user "Package Geometry/Pastemask Bottom")
		(5 "F.SilkS" user "Ref Des/Silkscreen Top")
		(7 "B.SilkS" user "Ref Des/Silkscreen Bottom")
		(1 "F.Mask" user "Board Geometry/Soldermask Top")
		(3 "B.Mask" user "Board Geometry/Soldermask Bottom")
		(17 "Dwgs.User" user "User.Drawings")
		(19 "Cmts.User" user "User.Comments")
		(21 "Eco1.User" user "User.Eco1")
		(23 "Eco2.User" user "User.Eco2")
		(25 "Edge.Cuts" user "Board Geometry/Outline")
		(27 "Margin" user)
		(31 "F.CrtYd" user "Package Geometry/Place Bound Top")
		(29 "B.CrtYd" user "Package Geometry/Place Bound Bottom")
		(35 "F.Fab" user "Ref Des/Assembly Top")
		(33 "B.Fab" user "Ref Des/Assembly Bottom")
	)
	(footprint ""
		(layer "F.Cu")
		(at 24.186642 -99.238816)
		(property "Reference" "C43"
			(at 0 0 0)
			(layer "F.SilkS")
			(hide yes)
			(effects
				(font
					(size 1.27 1.27)
				)
			)
		)
		(property "Value" "SCD1U16V2KX-L-GP"
			(at 1.1811 -2.7051 0)
			(unlocked yes)
			(layer "F.Fab")
			(hide yes)
			(effects
				(font
					(size 1.016 1.016)
					(thickness 0.1524)
				)
			)
		)
		(property "Device Type" "C402H22"
			(at 1.1811 -4.2291 0)
			(unlocked yes)
			(layer "F.Fab")
			(hide yes)
			(effects
				(font
					(size 1.016 1.016)
					(thickness 0.1524)
				)
			)
		)
		(duplicate_pad_numbers_are_jumpers no)
		(fp_rect
			(start -0.4318 0.9525)
			(end 0.4318 -0.9525)
			(stroke
				(width 0)
				(type default)
			)
			(fill no)
			(layer "F.CrtYd")
		)
		(fp_rect
			(start -0.4318 0.9525)
			(end 0.4318 -0.9525)
			(stroke
				(width 0)
				(type default)
			)
			(fill no)
			(layer "F.Fab")
		)
		(pad "1" smd custom
			(at 0 -0.4445)
			(size 0.1524 0.1524)
			(layers "F.Cu" "F.Mask" "F.Paste")
			(net "P5V_STBY")
			(options
				(clearance outline)
				(anchor circle)
			)
			(primitives
				(gr_poly
					(pts
						(arc
							(start 0.3048 -0.2032)
							(mid 0.275042 -0.275042)
							(end 0.2032 -0.3048)
						)
						(arc
							(start -0.2032 -0.3048)
							(mid -0.275042 -0.275042)
							(end -0.3048 -0.2032)
						)
						(arc
							(start -0.3048 0.2032)
							(mid -0.275042 0.275042)
							(end -0.2032 0.3048)
						)
						(arc
							(start 0.2032 0.3048)
							(mid 0.275042 0.275042)
							(end 0.3048 0.2032)
						)
					)
					(width 0)
					(fill yes)
				)
			)
		)
		(pad "2" smd custom
			(at 0 0.4445)
			(size 0.1524 0.1524)
			(layers "F.Cu" "F.Mask" "F.Paste")
			(net "GND")
			(options
				(clearance outline)
				(anchor circle)
			)
			(primitives
				(gr_poly
					(pts
						(arc
							(start 0.3048 -0.2032)
							(mid 0.275042 -0.275042)
							(end 0.2032 -0.3048)
						)
						(arc
							(start -0.2032 -0.3048)
							(mid -0.275042 -0.275042)
							(end -0.3048 -0.2032)
						)
						(arc
							(start -0.3048 0.2032)
							(mid -0.275042 0.275042)
							(end -0.2032 0.3048)
						)
						(arc
							(start 0.2032 0.3048)
							(mid 0.275042 0.275042)
							(end 0.3048 0.2032)
						)
					)
					(width 0)
					(fill yes)
				)
			)
		)
	)
	(footprint ""
		(layer "F.Cu")
		(at 230.251 -23.241 180)
		(property "Reference" "R3717"
			(at 0 0 180)
			(layer "F.SilkS")
			(hide yes)
			(effects
				(font
					(size 1.27 1.27)
				)
			)
		)
		(property "Value" "4K7R2F-GP"
			(at 0.064008 -3.993896 180)
			(unlocked yes)
			(layer "F.Fab")
			(hide yes)
			(effects
				(font
					(size 1.016 1.016)
					(thickness 0.1524)
				)
			)
		)
		(property "Device Type" "R402H16"
			(at 0.064008 -5.517896 180)
			(unlocked yes)
			(layer "F.Fab")
			(hide yes)
			(effects
				(font
					(size 1.016 1.016)
					(thickness 0.1524)
				)
			)
		)
		(duplicate_pad_numbers_are_jumpers no)
		(fp_line
			(start 0.508 -0.9398)
			(end -0.508 -0.9398)
			(stroke
				(width 0.1524)
				(type default)
			)
			(layer "F.SilkS")
		)
		(fp_line
			(start -0.508 -0.9398)
			(end -0.508 0.9398)
			(stroke
				(width 0.1524)
				(type default)
			)
			(layer "F.SilkS")
		)
		(fp_rect
			(start -0.508 0.9398)
			(end 0.508 -0.9398)
			(stroke
				(width 0)
				(type default)
			)
			(fill no)
			(layer "F.CrtYd")
		)
		(fp_rect
			(start -0.508 0.9398)
			(end 0.508 -0.9398)
			(stroke
				(width 0)
				(type default)
			)
			(fill no)
			(layer "F.Fab")
		)
		(pad "1" smd custom
			(at 0 -0.4445 180)
			(size 0.1397 0.1397)
			(layers "F.Cu" "F.Mask" "F.Paste")
			(net "HOST1_RST_N_LS")
			(options
				(clearance outline)
				(anchor circle)
			)
			(primitives
				(gr_poly
					(pts
						(arc
							(start -0.1778 -0.2794)
							(mid -0.249642 -0.249642)
							(end -0.2794 -0.1778)
						)
						(arc
							(start -0.2794 0.1778)
							(mid -0.249642 0.249642)
							(end -0.1778 0.2794)
						)
						(arc
							(start 0.1778 0.2794)
							(mid 0.249642 0.249642)
							(end 0.2794 0.1778)
						)
						(arc
							(start 0.2794 -0.1778)
							(mid 0.249642 -0.249642)
							(end 0.1778 -0.2794)
						)
					)
					(width 0)
					(fill yes)
				)
			)
		)
		(pad "2" smd custom
			(at 0 0.4445 180)
			(size 0.1397 0.1397)
			(layers "F.Cu" "F.Mask" "F.Paste")
			(net "GND")
			(options
				(clearance outline)
				(anchor circle)
			)
			(primitives
				(gr_poly
					(pts
						(arc
							(start -0.1778 -0.2794)
							(mid -0.249642 -0.249642)
							(end -0.2794 -0.1778)
						)
						(arc
							(start -0.2794 0.1778)
							(mid -0.249642 0.249642)
							(end -0.1778 0.2794)
						)
						(arc
							(start 0.1778 0.2794)
							(mid 0.249642 0.249642)
							(end 0.2794 0.1778)
						)
						(arc
							(start 0.2794 -0.1778)
							(mid 0.249642 -0.249642)
							(end 0.1778 -0.2794)
						)
					)
					(width 0)
					(fill yes)
				)
			)
		)
	)
	(footprint ""
		(layer "F.Cu")
		(at 151.511 -33.528)
		(property "Reference" "C388"
			(at 0 0 0)
			(layer "F.SilkS")
			(hide yes)
			(effects
				(font
					(size 1.27 1.27)
				)
			)
		)
		(property "Value" "SCD22U10V2KX-1GP"
			(at 1.1811 -2.7051 0)
			(unlocked yes)
			(layer "F.Fab")
			(hide yes)
			(effects
				(font
					(size 1.016 1.016)
					(thickness 0.1524)
				)
			)
		)
		(property "Device Type" "C402H22"
			(at 1.1811 -4.2291 0)
			(unlocked yes)
			(layer "F.Fab")
			(hide yes)
			(effects
				(font
					(size 1.016 1.016)
					(thickness 0.1524)
				)
			)
		)
		(duplicate_pad_numbers_are_jumpers no)
		(fp_rect
			(start -0.4318 0.9525)
			(end 0.4318 -0.9525)
			(stroke
				(width 0)
				(type default)
			)
			(fill no)
			(layer "F.CrtYd")
		)
		(fp_rect
			(start -0.4318 0.9525)
			(end 0.4318 -0.9525)
			(stroke
				(width 0)
				(type default)
			)
			(fill no)
			(layer "F.Fab")
		)
		(pad "1" smd custom
			(at 0 -0.4445)
			(size 0.1524 0.1524)
			(layers "F.Cu" "F.Mask" "F.Paste")
			(net "PCIE_TX_CAP_N84")
			(options
				(clearance outline)
				(anchor circle)
			)
			(primitives
				(gr_poly
					(pts
						(arc
							(start 0.3048 -0.2032)
							(mid 0.275042 -0.275042)
							(end 0.2032 -0.3048)
						)
						(arc
							(start -0.2032 -0.3048)
							(mid -0.275042 -0.275042)
							(end -0.3048 -0.2032)
						)
						(arc
							(start -0.3048 0.2032)
							(mid -0.275042 0.275042)
							(end -0.2032 0.3048)
						)
						(arc
							(start 0.2032 0.3048)
							(mid 0.275042 0.275042)
							(end 0.3048 0.2032)
						)
					)
					(width 0)
					(fill yes)
				)
			)
		)
		(pad "2" smd custom
			(at 0 0.4445)
			(size 0.1524 0.1524)
			(layers "F.Cu" "F.Mask" "F.Paste")
			(net "PCIE_TX_N84")
			(options
				(clearance outline)
				(anchor circle)
			)
			(primitives
				(gr_poly
					(pts
						(arc
							(start 0.3048 -0.2032)
							(mid 0.275042 -0.275042)
							(end 0.2032 -0.3048)
						)
						(arc
							(start -0.2032 -0.3048)
							(mid -0.275042 -0.275042)
							(end -0.3048 -0.2032)
						)
						(arc
							(start -0.3048 0.2032)
							(mid -0.275042 0.275042)
							(end -0.2032 0.3048)
						)
						(arc
							(start 0.2032 0.3048)
							(mid 0.275042 0.275042)
							(end 0.3048 0.2032)
						)
					)
					(width 0)
					(fill yes)
				)
			)
		)
	)
	(footprint ""
		(layer "F.Cu")
		(at 320.608198 -212.420454 180)
		(property "Reference" "C66"
			(at 0 0 180)
			(layer "F.SilkS")
			(hide yes)
			(effects
				(font
					(size 1.27 1.27)
				)
			)
		)
		(property "Value" "SCD22U10V2KX-1GP"
			(at 1.1811 -2.7051 180)
			(unlocked yes)
			(layer "F.Fab")
			(hide yes)
			(effects
				(font
					(size 1.016 1.016)
					(thickness 0.1524)
				)
			)
		)
		(property "Device Type" "C402H22"
			(at 1.1811 -4.2291 180)
			(unlocked yes)
			(layer "F.Fab")
			(hide yes)
			(effects
				(font
					(size 1.016 1.016)
					(thickness 0.1524)
				)
			)
		)
		(duplicate_pad_numbers_are_jumpers no)
		(fp_rect
			(start -0.4318 0.9525)
			(end 0.4318 -0.9525)
			(stroke
				(width 0)
				(type default)
			)
			(fill no)
			(layer "F.CrtYd")
		)
		(fp_rect
			(start -0.4318 0.9525)
			(end 0.4318 -0.9525)
			(stroke
				(width 0)
				(type default)
			)
			(fill no)
			(layer "F.Fab")
		)
		(pad "1" smd custom
			(at 0 -0.4445 180)
			(size 0.1524 0.1524)
			(layers "F.Cu" "F.Mask" "F.Paste")
			(net "PCIE_TX_CAP_N22")
			(options
				(clearance outline)
				(anchor circle)
			)
			(primitives
				(gr_poly
					(pts
						(arc
							(start 0.3048 -0.2032)
							(mid 0.275042 -0.275042)
							(end 0.2032 -0.3048)
						)
						(arc
							(start -0.2032 -0.3048)
							(mid -0.275042 -0.275042)
							(end -0.3048 -0.2032)
						)
						(arc
							(start -0.3048 0.2032)
							(mid -0.275042 0.275042)
							(end -0.2032 0.3048)
						)
						(arc
							(start 0.2032 0.3048)
							(mid 0.275042 0.275042)
							(end 0.3048 0.2032)
						)
					)
					(width 0)
					(fill yes)
				)
			)
		)
		(pad "2" smd custom
			(at 0 0.4445 180)
			(size 0.1524 0.1524)
			(layers "F.Cu" "F.Mask" "F.Paste")
			(net "PCIE_TX_N22")
			(options
				(clearance outline)
				(anchor circle)
			)
			(primitives
				(gr_poly
					(pts
						(arc
							(start 0.3048 -0.2032)
							(mid 0.275042 -0.275042)
							(end 0.2032 -0.3048)
						)
						(arc
							(start -0.2032 -0.3048)
							(mid -0.275042 -0.275042)
							(end -0.3048 -0.2032)
						)
						(arc
							(start -0.3048 0.2032)
							(mid -0.275042 0.275042)
							(end -0.2032 0.3048)
						)
						(arc
							(start 0.2032 0.3048)
							(mid 0.275042 0.275042)
							(end 0.3048 0.2032)
						)
					)
					(width 0)
					(fill yes)
				)
			)
		)
	)
	(footprint ""
		(layer "F.Cu")
		(at 125.599952 -1.999996 90)
		(property "Reference" "LED11"
			(at 0 0 90)
			(layer "F.SilkS")
			(hide yes)
			(effects
				(font
					(size 1.27 1.27)
				)
			)
		)
		(property "Value" "LED-YG-51-GP"
			(at -2.6924 -1.4224 90)
			(unlocked yes)
			(layer "F.Fab")
			(hide yes)
			(effects
				(font
					(size 1.016 1.016)
					(thickness 0.1524)
				)
			)
		)
		(property "Device Type" "LED1608AKH40"
			(at -2.6924 -2.9464 90)
			(unlocked yes)
			(layer "F.Fab")
			(hide yes)
			(effects
				(font
					(size 1.016 1.016)
					(thickness 0.1524)
				)
			)
		)
		(duplicate_pad_numbers_are_jumpers no)
		(fp_line
			(start 0.6604 -1.3716)
			(end 0.6604 1.3716)
			(stroke
				(width 0.1524)
				(type default)
			)
			(layer "F.SilkS")
		)
		(fp_line
			(start -0.6604 -1.3716)
			(end 0.6604 -1.3716)
			(stroke
				(width 0.1524)
				(type default)
			)
			(layer "F.SilkS")
		)
		(fp_line
			(start 0.6604 1.3716)
			(end -0.6604 1.3716)
			(stroke
				(width 0.1524)
				(type default)
			)
			(layer "F.SilkS")
		)
		(fp_line
			(start -0.6604 1.3716)
			(end -0.6604 -1.3716)
			(stroke
				(width 0.1524)
				(type default)
			)
			(layer "F.SilkS")
		)
		(fp_line
			(start -0.5969 1.5494)
			(end 0.5842 1.5494)
			(stroke
				(width 0.508)
				(type default)
			)
			(layer "F.SilkS")
		)
		(fp_line
			(start 0.7493 1.651)
			(end 0.7493 1.1811)
			(stroke
				(width 0.3302)
				(type default)
			)
			(layer "F.SilkS")
		)
		(fp_line
			(start -0.7493 1.651)
			(end -0.7493 1.1811)
			(stroke
				(width 0.3302)
				(type default)
			)
			(layer "F.SilkS")
		)
		(fp_rect
			(start -0.6223 1.3335)
			(end 0.6223 -1.3335)
			(stroke
				(width 0)
				(type default)
			)
			(fill no)
			(layer "F.CrtYd")
		)
		(fp_rect
			(start -0.6223 1.3335)
			(end 0.6223 -1.3335)
			(stroke
				(width 0)
				(type default)
			)
			(fill no)
			(layer "F.Fab")
		)
		(pad "A" smd custom
			(at 0 -0.762 90)
			(size 0.2159 0.2159)
			(layers "F.Cu" "F.Mask" "F.Paste")
			(net "LED_R_4")
			(options
				(clearance outline)
				(anchor circle)
			)
			(primitives
				(gr_poly
					(pts
						(arc
							(start -0.3302 -0.4318)
							(mid -0.402042 -0.402042)
							(end -0.4318 -0.3302)
						)
						(arc
							(start -0.4318 0.3302)
							(mid -0.402042 0.402042)
							(end -0.3302 0.4318)
						)
						(arc
							(start 0.3302 0.4318)
							(mid 0.402042 0.402042)
							(end 0.4318 0.3302)
						)
						(arc
							(start 0.4318 -0.3302)
							(mid 0.402042 -0.402042)
							(end 0.3302 -0.4318)
						)
					)
					(width 0)
					(fill yes)
				)
			)
		)
		(pad "K" smd custom
			(at 0 0.762 90)
			(size 0.2159 0.2159)
			(layers "F.Cu" "F.Mask" "F.Paste")
			(net "LED_Q_4")
			(options
				(clearance outline)
				(anchor circle)
			)
			(primitives
				(gr_poly
					(pts
						(arc
							(start -0.3302 -0.4318)
							(mid -0.402042 -0.402042)
							(end -0.4318 -0.3302)
						)
						(arc
							(start -0.4318 0.3302)
							(mid -0.402042 0.402042)
							(end -0.3302 0.4318)
						)
						(arc
							(start 0.3302 0.4318)
							(mid 0.402042 0.402042)
							(end 0.4318 0.3302)
						)
						(arc
							(start 0.4318 -0.3302)
							(mid 0.402042 -0.402042)
							(end 0.3302 -0.4318)
						)
					)
					(width 0)
					(fill yes)
				)
			)
		)
	)
	(footprint ""
		(layer "F.Cu")
		(at 323.56171 -33.482788)
		(property "Reference" "C48"
			(at 0 0 0)
			(layer "F.SilkS")
			(hide yes)
			(effects
				(font
					(size 1.27 1.27)
				)
			)
		)
		(property "Value" "SCD22U10V2KX-1GP"
			(at 1.1811 -2.7051 0)
			(unlocked yes)
			(layer "F.Fab")
			(hide yes)
			(effects
				(font
					(size 1.016 1.016)
					(thickness 0.1524)
				)
			)
		)
		(property "Device Type" "C402H22"
			(at 1.1811 -4.2291 0)
			(unlocked yes)
			(layer "F.Fab")
			(hide yes)
			(effects
				(font
					(size 1.016 1.016)
					(thickness 0.1524)
				)
			)
		)
		(duplicate_pad_numbers_are_jumpers no)
		(fp_rect
			(start -0.4318 0.9525)
			(end 0.4318 -0.9525)
			(stroke
				(width 0)
				(type default)
			)
			(fill no)
			(layer "F.CrtYd")
		)
		(fp_rect
			(start -0.4318 0.9525)
			(end 0.4318 -0.9525)
			(stroke
				(width 0)
				(type default)
			)
			(fill no)
			(layer "F.Fab")
		)
		(pad "1" smd custom
			(at 0 -0.4445)
			(size 0.1524 0.1524)
			(layers "F.Cu" "F.Mask" "F.Paste")
			(net "PCIE_TX_CAP_P13")
			(options
				(clearance outline)
				(anchor circle)
			)
			(primitives
				(gr_poly
					(pts
						(arc
							(start 0.3048 -0.2032)
							(mid 0.275042 -0.275042)
							(end 0.2032 -0.3048)
						)
						(arc
							(start -0.2032 -0.3048)
							(mid -0.275042 -0.275042)
							(end -0.3048 -0.2032)
						)
						(arc
							(start -0.3048 0.2032)
							(mid -0.275042 0.275042)
							(end -0.2032 0.3048)
						)
						(arc
							(start 0.2032 0.3048)
							(mid 0.275042 0.275042)
							(end 0.3048 0.2032)
						)
					)
					(width 0)
					(fill yes)
				)
			)
		)
		(pad "2" smd custom
			(at 0 0.4445)
			(size 0.1524 0.1524)
			(layers "F.Cu" "F.Mask" "F.Paste")
			(net "PCIE_TX_P13")
			(options
				(clearance outline)
				(anchor circle)
			)
			(primitives
				(gr_poly
					(pts
						(arc
							(start 0.3048 -0.2032)
							(mid 0.275042 -0.275042)
							(end 0.2032 -0.3048)
						)
						(arc
							(start -0.2032 -0.3048)
							(mid -0.275042 -0.275042)
							(end -0.3048 -0.2032)
						)
						(arc
							(start -0.3048 0.2032)
							(mid -0.275042 0.275042)
							(end -0.2032 0.3048)
						)
						(arc
							(start 0.2032 0.3048)
							(mid 0.275042 0.275042)
							(end 0.3048 0.2032)
						)
					)
					(width 0)
					(fill yes)
				)
			)
		)
	)
	(footprint ""
		(layer "F.Cu")
		(at 41.148 -201.549 90)
		(property "Reference" "U30"
			(at 0 0 90)
			(layer "F.SilkS")
			(hide yes)
			(effects
				(font
					(size 1.27 1.27)
				)
			)
		)
		(property "Value" "PCA9511ADP-T-GP"
			(at 0 -13.1572 90)
			(unlocked yes)
			(layer "F.Fab")
			(hide yes)
			(effects
				(font
					(size 1.016 1.016)
					(thickness 0.1524)
				)
			)
		)
		(property "Device Type" "SSOIC8-2H44"
			(at 0 -15.1892 90)
			(unlocked yes)
			(layer "F.Fab")
			(hide yes)
			(effects
				(font
					(size 1.016 1.016)
					(thickness 0.1524)
				)
			)
		)
		(duplicate_pad_numbers_are_jumpers no)
		(fp_line
			(start 1.0922 -1.016)
			(end 1.0922 1.016)
			(stroke
				(width 0.1524)
				(type default)
			)
			(layer "F.SilkS")
		)
		(fp_line
			(start -1.9304 -1.016)
			(end 1.0922 -1.016)
			(stroke
				(width 0.1524)
				(type default)
			)
			(layer "F.SilkS")
		)
		(fp_line
			(start -1.524 0)
			(end -1.9304 -0.4064)
			(stroke
				(width 0.1524)
				(type default)
			)
			(layer "F.SilkS")
		)
		(fp_line
			(start -1.524 0)
			(end -1.9304 0.4064)
			(stroke
				(width 0.1524)
				(type default)
			)
			(layer "F.SilkS")
		)
		(fp_line
			(start 1.0922 1.016)
			(end -1.9304 1.016)
			(stroke
				(width 0.1524)
				(type default)
			)
			(layer "F.SilkS")
		)
		(fp_line
			(start -1.9304 1.016)
			(end -1.9304 -1.016)
			(stroke
				(width 0.1524)
				(type default)
			)
			(layer "F.SilkS")
		)
		(fp_line
			(start -1.7018 1.0414)
			(end -1.7018 2.9718)
			(stroke
				(width 0.635)
				(type default)
			)
			(layer "F.SilkS")
		)
		(fp_poly
			(pts
				(xy -1.1938 -1.016) (xy 1.0922 -1.016) (xy 1.0922 1.016) (xy -1.1938 1.016)
			)
			(stroke
				(width 0)
				(type default)
			)
			(fill yes)
			(layer "F.SilkS")
		)
		(fp_rect
			(start -2.0066 3.3401)
			(end 2.0066 -3.3401)
			(stroke
				(width 0)
				(type default)
			)
			(fill no)
			(layer "F.CrtYd")
		)
		(fp_poly
			(pts
				(xy -2.0066 -3.3401) (xy 2.0066 -3.3401) (xy 2.0066 3.3401) (xy -2.0066 3.3401)
			)
			(stroke
				(width 0)
				(type default)
			)
			(fill no)
			(layer "F.Fab")
		)
		(pad "1" smd rect
			(at -0.97536 2.0701 90)
			(size 0.4064 1.524)
			(layers "F.Cu" "F.Mask" "F.Paste")
			(net "I2C6_BUFF_EN")
		)
		(pad "2" smd rect
			(at -0.32512 2.0701 90)
			(size 0.4064 1.524)
			(layers "F.Cu" "F.Mask" "F.Paste")
			(net "BMC_I2C6_C_FCB_SCL_R")
		)
		(pad "3" smd rect
			(at 0.32512 2.0701 90)
			(size 0.4064 1.524)
			(layers "F.Cu" "F.Mask" "F.Paste")
			(net "BUF_I2C6_C_FCB_SCL_R")
		)
		(pad "4" smd rect
			(at 0.97536 2.0701 90)
			(size 0.4064 1.524)
			(layers "F.Cu" "F.Mask" "F.Paste")
			(net "GND")
		)
		(pad "5" smd rect
			(at 0.97536 -2.0701 90)
			(size 0.4064 1.524)
			(layers "F.Cu" "F.Mask" "F.Paste")
			(net "I2C6_BUF_READY")
		)
		(pad "6" smd rect
			(at 0.32512 -2.0701 90)
			(size 0.4064 1.524)
			(layers "F.Cu" "F.Mask" "F.Paste")
			(net "BUF_I2C6_C_FCB_SDA_R")
		)
		(pad "7" smd rect
			(at -0.32512 -2.0701 90)
			(size 0.4064 1.524)
			(layers "F.Cu" "F.Mask" "F.Paste")
			(net "BMC_I2C6_C_FCB_SDA_R")
		)
		(pad "8" smd rect
			(at -0.97536 -2.0701 90)
			(size 0.4064 1.524)
			(layers "F.Cu" "F.Mask" "F.Paste")
			(net "P3V3_STBY")
		)
	)
)
